# S9S_MB_2U (Grand Teton) — schematic netlist excerpt (pin names and nets, part order shuffled) for the footprints in the layout excerpt that follows; sources: Cadence DE-HDL packaged netlist, KiCad conversion of 03242023_DA0F0TMBIJ0_F0T_Motherboard_J_brd_V01_OCP.brd

C84  Q_CAP  2.2UF 6.3V 20% X6S  pkg C0402  page 109 : A = P3V3_AUX ; B = GND
R1217  Q_RES  1.5K 1% CHIP  pkg 0402LF  page 80 : A = P3V3_AUX ; B = FM_S3M_CPU1_CPLD_CRC_ERROR

(kicad_pcb
	(version 20260206)
	(generator "pcbnew")
	(generator_version "10.0")
	(general
		(thickness 1.6)
		(legacy_teardrops no)
	)
	(paper "A4")
	(title_block
		(title "03242023_DA0F0TMBIJ0_F0T_Motherboard_J_brd_V01_OCP.brd")
		(comment 1 "Grand Teton / footprints 5368-5369 of 6105")
	)
	(layers
		(0 "F.Cu" signal "TOP")
		(4 "In1.Cu" signal "GND")
		(6 "In2.Cu" signal "IN1")
		(8 "In3.Cu" signal "GND1")
		(10 "In4.Cu" signal "IN2")
		(12 "In5.Cu" signal "GND2")
		(14 "In6.Cu" signal "IN3")
		(16 "In7.Cu" signal "GND3")
		(18 "In8.Cu" signal "VCC")
		(20 "In9.Cu" signal "VCC1")
		(22 "In10.Cu" signal "GND4")
		(24 "In11.Cu" signal "IN4")
		(26 "In12.Cu" signal "GND5")
		(28 "In13.Cu" signal "IN5")
		(30 "In14.Cu" signal "GND6")
		(32 "In15.Cu" signal "IN6")
		(34 "In16.Cu" signal "GND7")
		(2 "B.Cu" signal "BOTTOM")
		(9 "F.Adhes" user "F.Adhesive")
		(11 "B.Adhes" user "B.Adhesive")
		(13 "F.Paste" user "Package Geometry/Pastemask Top")
		(15 "B.Paste" user "Package Geometry/Pastemask Bottom")
		(5 "F.SilkS" user "Ref Des/Silkscreen Top")
		(7 "B.SilkS" user "Ref Des/Silkscreen Bottom")
		(1 "F.Mask" user "Board Geometry/Soldermask Top")
		(3 "B.Mask" user "Board Geometry/Soldermask Bottom")
		(17 "Dwgs.User" user "User.Drawings")
		(19 "Cmts.User" user "User.Comments")
		(21 "Eco1.User" user "User.Eco1")
		(23 "Eco2.User" user "User.Eco2")
		(25 "Edge.Cuts" user "Board Geometry/Outline")
		(27 "Margin" user)
		(31 "F.CrtYd" user "Package Geometry/Place Bound Top")
		(29 "B.CrtYd" user "Package Geometry/Place Bound Bottom")
		(35 "F.Fab" user "Ref Des/Assembly Top")
		(33 "B.Fab" user "Ref Des/Assembly Bottom")
	)
	(footprint ""
		(layer "B.Cu")
		(at 173.913546 -319.268856 180)
		(property "Reference" "C84"
			(at 0 0 0)
			(layer "B.SilkS")
			(hide yes)
			(effects
				(font
					(size 1.27 1.27)
				)
				(justify mirror)
			)
		)
		(property "Value" ""
			(at 0 0 0)
			(layer "B.Fab")
			(effects
				(font
					(size 1.27 1.27)
				)
				(justify mirror)
			)
		)
		(duplicate_pad_numbers_are_jumpers no)
		(fp_line
			(start 0.7874 0.4064)
			(end 0.7874 -0.4064)
			(stroke
				(width 0.1524)
				(type default)
			)
			(layer "B.SilkS")
		)
		(fp_line
			(start 0.7874 -0.4064)
			(end -0.7874 -0.4064)
			(stroke
				(width 0.1524)
				(type default)
			)
			(layer "B.SilkS")
		)
		(fp_line
			(start -0.7874 0.4064)
			(end 0.7874 0.4064)
			(stroke
				(width 0.1524)
				(type default)
			)
			(layer "B.SilkS")
		)
		(fp_line
			(start -0.7874 -0.4064)
			(end -0.7874 0.4064)
			(stroke
				(width 0.1524)
				(type default)
			)
			(layer "B.SilkS")
		)
		(fp_line
			(start 0.67945 0.3048)
			(end 0.67945 -0.305054)
			(stroke
				(width 0.1)
				(type default)
			)
			(layer "B.Fab")
		)
		(fp_line
			(start 0.67945 -0.305054)
			(end 0.12065 -0.305054)
			(stroke
				(width 0.1)
				(type default)
			)
			(layer "B.Fab")
		)
		(fp_line
			(start 0.12065 0.3048)
			(end 0.67945 0.3048)
			(stroke
				(width 0.1)
				(type default)
			)
			(layer "B.Fab")
		)
		(fp_line
			(start 0.12065 0.2794)
			(end 0.12065 0.3048)
			(stroke
				(width 0.1)
				(type default)
			)
			(layer "B.Fab")
		)
		(fp_line
			(start 0.12065 -0.2794)
			(end -0.12065 -0.2794)
			(stroke
				(width 0.1)
				(type default)
			)
			(layer "B.Fab")
		)
		(fp_line
			(start 0.12065 -0.305054)
			(end 0.12065 -0.2794)
			(stroke
				(width 0.1)
				(type default)
			)
			(layer "B.Fab")
		)
		(fp_line
			(start -0.120396 0.3048)
			(end -0.120396 0.2794)
			(stroke
				(width 0.1)
				(type default)
			)
			(layer "B.Fab")
		)
		(fp_line
			(start -0.120396 0.2794)
			(end 0.12065 0.2794)
			(stroke
				(width 0.1)
				(type default)
			)
			(layer "B.Fab")
		)
		(fp_line
			(start -0.12065 -0.2794)
			(end -0.12065 -0.3048)
			(stroke
				(width 0.1)
				(type default)
			)
			(layer "B.Fab")
		)
		(fp_line
			(start -0.12065 -0.3048)
			(end -0.67945 -0.3048)
			(stroke
				(width 0.1)
				(type default)
			)
			(layer "B.Fab")
		)
		(fp_line
			(start -0.67945 0.3048)
			(end -0.120396 0.3048)
			(stroke
				(width 0.1)
				(type default)
			)
			(layer "B.Fab")
		)
		(fp_line
			(start -0.67945 -0.3048)
			(end -0.67945 0.3048)
			(stroke
				(width 0.1)
				(type default)
			)
			(layer "B.Fab")
		)
		(pad "1" smd circle
			(at 0.40005 0)
			(size 0 0)
			(layers "B.Cu" "B.Mask" "B.Paste")
			(net "P3V3_AUX")
		)
		(pad "2" smd circle
			(at -0.40005 0)
			(size 0 0)
			(layers "B.Cu" "B.Mask" "B.Paste")
			(net "GND")
		)
	)
	(footprint ""
		(layer "B.Cu")
		(at 156.1465 -190.99911 90)
		(property "Reference" "R1217"
			(at 0 0 90)
			(layer "B.SilkS")
			(hide yes)
			(effects
				(font
					(size 1.27 1.27)
				)
				(justify mirror)
			)
		)
		(property "Value" ""
			(at 0 0 90)
			(layer "B.Fab")
			(effects
				(font
					(size 1.27 1.27)
				)
				(justify mirror)
			)
		)
		(duplicate_pad_numbers_are_jumpers no)
		(fp_line
			(start 0.7874 -0.4064)
			(end -0.7874 -0.4064)
			(stroke
				(width 0.1524)
				(type default)
			)
			(layer "B.SilkS")
		)
		(fp_line
			(start -0.7874 -0.4064)
			(end -0.7874 0.4064)
			(stroke
				(width 0.1524)
				(type default)
			)
			(layer "B.SilkS")
		)
		(fp_line
			(start 0.7874 0.4064)
			(end 0.7874 -0.4064)
			(stroke
				(width 0.1524)
				(type default)
			)
			(layer "B.SilkS")
		)
		(fp_line
			(start -0.7874 0.4064)
			(end 0.7874 0.4064)
			(stroke
				(width 0.1524)
				(type default)
			)
			(layer "B.SilkS")
		)
		(fp_line
			(start 0.67945 -0.305054)
			(end 0.12065 -0.305054)
			(stroke
				(width 0.1)
				(type default)
			)
			(layer "B.Fab")
		)
		(fp_line
			(start 0.12065 -0.305054)
			(end 0.12065 -0.2794)
			(stroke
				(width 0.1)
				(type default)
			)
			(layer "B.Fab")
		)
		(fp_line
			(start -0.12065 -0.3048)
			(end -0.67945 -0.3048)
			(stroke
				(width 0.1)
				(type default)
			)
			(layer "B.Fab")
		)
		(fp_line
			(start -0.67945 -0.3048)
			(end -0.67945 0.3048)
			(stroke
				(width 0.1)
				(type default)
			)
			(layer "B.Fab")
		)
		(fp_line
			(start 0.12065 -0.2794)
			(end -0.12065 -0.2794)
			(stroke
				(width 0.1)
				(type default)
			)
			(layer "B.Fab")
		)
		(fp_line
			(start -0.12065 -0.2794)
			(end -0.12065 -0.3048)
			(stroke
				(width 0.1)
				(type default)
			)
			(layer "B.Fab")
		)
		(fp_line
			(start 0.12065 0.2794)
			(end 0.12065 0.3048)
			(stroke
				(width 0.1)
				(type default)
			)
			(layer "B.Fab")
		)
		(fp_line
			(start -0.120396 0.2794)
			(end 0.12065 0.2794)
			(stroke
				(width 0.1)
				(type default)
			)
			(layer "B.Fab")
		)
		(fp_line
			(start 0.67945 0.3048)
			(end 0.67945 -0.305054)
			(stroke
				(width 0.1)
				(type default)
			)
			(layer "B.Fab")
		)
		(fp_line
			(start 0.12065 0.3048)
			(end 0.67945 0.3048)
			(stroke
				(width 0.1)
				(type default)
			)
			(layer "B.Fab")
		)
		(fp_line
			(start -0.120396 0.3048)
			(end -0.120396 0.2794)
			(stroke
				(width 0.1)
				(type default)
			)
			(layer "B.Fab")
		)
		(fp_line
			(start -0.67945 0.3048)
			(end -0.120396 0.3048)
			(stroke
				(width 0.1)
				(type default)
			)
			(layer "B.Fab")
		)
		(pad "1" smd circle
			(at 0.40005 0 270)
			(size 0 0)
			(layers "B.Cu" "B.Mask" "B.Paste")
			(net "P3V3_AUX")
		)
		(pad "2" smd circle
			(at -0.40005 0 270)
			(size 0 0)
			(layers "B.Cu" "B.Mask" "B.Paste")
			(net "FM_S3M_CPU1_CPLD_CRC_ERROR")
		)
	)
)
